# S9S_MB_2U (Grand Teton) — schematic parts with pin connectivity, parts 5983–6004 of 6093; source: Cadence DE-HDL packaged netlist (pstxprt.dat, pstxnet.dat, pstchip.dat)

U249  LCMXO3LF9400C5BG484C  LCMXO3LF-9400C-5BG484C IC  pkg BGA484_0-8_19X19_H67  page 216  (pins 330-484 of 484)
  N22  PR19A  BI  = FM_CPU1_PROC_ID0
  P1  PL18B  BI  = NC
  P2  PL19A  BI  = NC
  P3  PL19C  BI  = NC
  P4  PL20A  BI  = NC
  P5  PL21C  BI  = PWRGD_CPUPWRGD_LVC2_R1
  P6  PL21D  BI  = NC
  P7  PL24D  BI  = H_CPU1_THERMTRIP_LVC1_N
  P8  VCCIO3_2  POWER  = P3V3_AUX_FPGA_VCCIO3
  P9  GND38  POWER  = GND
  P10  GND39  POWER  = GND
  P11  GND40  POWER  = GND
  P12  GND41  POWER  = GND
  P13  GND42  POWER  = GND
  P14  GND43  POWER  = GND
  P15  VCCIO1_8  POWER  = P3V3_AUX_FPGA_VCCIO1
  P16  PR24B  BI  = FM_CPU_RMCA_CATERR_DLY_LVT3_R_N
  P17  PR24A  BI  = FM_RST_PERST_BIT1
  P18  PR21D  BI  = FM_RST_PERST_BIT0
  P19  PR21C  BI  = IRQ_PVCCIN_CPU1_VRHOT_R_N
  P20  PR20D  BI  = FM_CPU1_PKGID2
  P21  PR19B  BI  = FM_CPU1_PROC_ID1
  P22  PR20C  BI  = FM_CPU1_PKGID1
  R1  PL19B  BI  = NC
  R2  PL21A  BI  = NC
  R3  PL24A  BI  = NC
  R4  PL24B  BI  = NC
  R5  PL24C  BI  = NC
  R6  PL25C  BI  = H_CPU0_MEMTRIP_LVC1_N
  R7  PL25D  BI  = H_CPU1_MEMHOT_OUT_LVC1_N
  R8  GND44  POWER  = GND
  R9  VCCIO2_1  POWER  = P3V3_AUX_FPGA_VCCIO2
  R10  VCCIO2_2  POWER  = P3V3_AUX_FPGA_VCCIO2
  R11  VCCIO2_3  POWER  = P3V3_AUX_FPGA_VCCIO2
  R12  VCCIO2_4  POWER  = P3V3_AUX_FPGA_VCCIO2
  R13  VCCIO2_5  POWER  = P3V3_AUX_FPGA_VCCIO2
  R14  VCCIO2_6  POWER  = P3V3_AUX_FPGA_VCCIO2
  R15  GND45  POWER  = GND
  R16  PR26C  BI  = PWRGD_FAIL_CPU1_CD_R
  R17  PR26B  BI  = PWRGD_FAIL_CPU1_AB_R
  R18  PR26A  BI  = PWRGD_FAIL_CPU0_GH_R
  R19  PR25D  BI  = PWRGD_FAIL_CPU0_EF_R
  R20  PR25C  BI  = PWRGD_FAIL_CPU0_CD_R
  R21  PR20B  BI  = FM_CPU1_PKGID0
  R22  PR20A  BI  = FM_CPU0_PKGID2
  T1  PL21B  BI  = NC
  T2  PL25A  BI  = H_CPU0_THERMTRIP_LVC1_N
  T3  PL26A  BI  = H_CPU0_MEMHOT_OUT_LVC1_N
  T4  PL26B  BI  = H_CPU_ERR2_LVC2_N
  T5  PL26C  BI  = H_CPU_ERR1_LVC2_N
  T6  PL26D  BI  = H_CPU_ERR0_LVC2_N
  T7  PL30D  BI  = H_CPU0_MEMHOT_IN_LVC1_R_N
  T8  PB8D  BI  = FM_PLD_CLK_25M_R_EN
  T9  \pb16a||mclk||cclk\  BI  = FM_BIOS_POST_CMPLT_BMC_N
  T10  PB19C  BI  = FM_PLD_HEARTBEAT_LVC3
  T11  PB22C  BI  = GPU_3V3IO_RSVD0_FFU_ISO_R
  T12  PB27B  BI  = GPU_3V3IO_RSVD1_ISO_R
  T13  PB32A  BI  = RST_SGPIO_RESET_N_R
  T14  PB32B  BI  = FM_ME_BT_DONE
  T15  PB43C  BI  = CLK_SWB_BUF2_OE_N
  T16  PB46D  BI  = FM_AC_PWR_BTN_PLD_ISO_N
  T17  PR27C  BI  = OCP_V3_2_MAIN_PWR_EN
  T18  PR27B  BI  = OCP_SFF_MAIN_PWR_EN
  T19  PR27A  BI  = PWRGD_FAIL_CPU1_GH_R
  T20  PR26D  BI  = PWRGD_FAIL_CPU1_EF_R
  T21  PR21B  BI  = IRQ_PVCCIN_CPU0_VRHOT_R_N
  T22  PR21A  BI  = PWRGD_DSW_PWROK_R3
  U1  PL25B  BI  = H_CPU1_MEMTRIP_LVC1_N
  U2  \pl27a||pclkt3_0\  BI  = NC
  U3  PL27C  BI  = NC
  U4  PL27D  BI  = NC
  U5  PL28D  BI  = RST_CPU0_LVC1_R_N
  U6  PB5D  BI  = FM_ADR_COMPLETE
  U7  PB8C  BI  = FM_PLD_CLKS_DEV_R_EN
  U8  PB13D  BI  = FM_BMC_DBP_PRESENT_R_N
  U9  \pb16b||so||spiso\  BI  = FM_BMC_RSTBTN_OUT_N
  U10  PB19D  BI  = FM_FORCE_PWRON_LVC3
  U11  PB22D  BI  = GPU_3V3IO_RSVD1_FFU_ISO_R
  U12  PB27C  BI  = GPU_3V3IO_RSVD3_ISO_R
  U13  PB29D  BI  = IRQ_BMC_CPU_NMI_R1
  U14  PB32C  BI  = RST_PCIE_PCH_DEV_PERST_N
  U15  PB38D  BI  = FM_SLPS3_PLD_N
  U16  PB43D  BI  = NC_FPGA_PB43D
  U17  PR29C  BI  = FM_JTAG_TCK_MUX_SEL_R
  U18  PR28D  BI  = E1S_0_LED_ACT_R_N
  U19  PR28C  BI  = FM_SMB_2_ALERT_GPU_ISO_R_N
  U20  PR27D  BI  = HP_LVC3_OCP_V3_2_HSC_PWRGD_PLD_
  U21  PR24D  BI  = FM_SLPS4_PLD_N
  U22  PR24C  BI  = FM_JTAG_BMC_MUX_SEL_R
  V1  \pl27b||pclkc3_0\  BI  = NC
  V2  GND46  POWER  = GND
  V3  VCCIO3_3  POWER  = P3V3_AUX_FPGA_VCCIO3
  V4  PL28C  BI  = RST_CPU1_LVC1_R_N
  V5  PL30C  BI  = H_CPU1_MEMHOT_IN_LVC1_R_N
  V6  PB5C  BI  = FM_ADR_TRIGGER_N
  V7  PB11D  BI  = RST_PFR_OVR_SRTC_R
  V8  PB13C  BI  = FM_REMOTE_DEBUG_DET
  V9  PB16C  BI  = FM_PS_PWROK_DLY_SEL
  V10  PB21A  BI  = E1S_0_PRSNT_N
  V11  PB24C  BI  = PRSNT_CABLE_GPU_A2_ISO_R_N
  V12  PB27D  BI  = GPU_3V3IO_RSVD4_ISO_R
  V13  PB29C  BI  = IRQ_PCH_CPU_NMI_EVENT_N
  V14  PB32D  BI  = NC_FPGA_PB32D
  V15  PB38C  BI  = ROT_P1_RST_IND_N_R
  V16  PB40D  BI  = RST_RSMRST_PLD_R_N
  V17  PB46C  BI  = FM_PDB_BUF_EN
  V18  PR30A  BI  = FM_BMC_CPU_FBRK_OUT_R_N
  V19  PR29D  BI  = CLK_GEN2_GPU_FPGA_OE_R_N
  V20  VCCIO1_9  POWER  = P3V3_AUX_FPGA_VCCIO1
  V21  GND47  POWER  = GND
  V22  PR25A  BI  = FM_PS_EN_PLD_R
  W1  PL28A  BI  = PWRGD_CPU1_LVC1_R
  W2  PL28B  BI  = PWRGD_CPU0_LVC1_R
  W3  PL29C  BI  = FM_THERMTRIP_DLY_LVC1_R_N
  W4  PL30B  BI  = H_CPU0_PROCHOT_LVC1_R_N
  W5  PB7D  BI  = NC_FPGA_PB7D
  W6  PB11C  BI  = RST_PFR_OVR_RTC_R
  W7  VCCIO2_7  POWER  = P3V3_AUX_FPGA_VCCIO2
  W8  PB16D  BI  = FM_RST_PERST_BIT2
  W9  PB18D  BI  = USB_OC1_REAR_N
  W10  PB21B  BI  = HSC_D_OC_R1
  W11  VCCIO2_8  POWER  = P3V3_AUX_FPGA_VCCIO2
  W12  GND48  POWER  = GND
  W13  PB30D  BI  = IRQ_PCH_SCI_WHEA_R_N
  W14  PB33D  BI  = FM_BIOS_DEBUG_EN_N
  W15  PB35D  BI  = FM_DIMM_12V_CPS_SX_N
  W16  VCCIO2_9  POWER  = P3V3_AUX_FPGA_VCCIO2
  W17  PB41D  BI  = CLK_SWB_OE_N
  W18  PB44D  BI  = SWB_HSC_PWRGD_ISO_R
  W19  PR30C  BI  = RST_PERST_SWB_N
  W20  PR30B  BI  = FM_PCH_SPKR_R
  W21  PR28B  BI  = FM_SMB_1_ALERT_GPU_ISO_R_N
  W22  PR25B  BI  = PWRGD_FAIL_CPU0_AB_R
  Y1  PL29A  BI  = H_CPU_RMCA_LVC2_R2_N
  Y2  PL29D  BI  = H_CPU_CATERR_LVC2_R2_N
  Y3  PL30A  BI  = H_CPU1_PROCHOT_LVC1_R_N
  Y4  PB7C  BI  = IRQ_UV_DETECT_R_N
  Y5  PB10C  BI  = PCIE_M2_SSD0_PRSNT_N
  Y6  PB10D  BI  = FM_HBM2_HBM3_VPP_SEL
  Y7  GND49  POWER  = GND
  Y8  PB18C  BI  = FM_ME_AUTHN_FAIL
  Y9  PB21C  BI  = PRSNT_SWB_ISO_R_N
  Y10  PB21D  BI  = FM_PCH_BMC_RST_N
  Y11  PB24D  BI  = GPU_3V3IO_RSVD5_FFU_ISO_R
  Y12  PB27A  BI  = PRSNT_CABLE_GPU_A1_ISO_R_N
  Y13  PB30C  BI  = IRQ_PSU_ALERT_R_N
  Y14  PB33C  BI  = FM_NCSI_OCP_V3_1_R_OE
  Y15  PB35C  BI  = FM_THROTTLE_R_N
  Y16  GND50  POWER  = GND
  Y17  PB40C  BI  = RST_PLTRST_PLD_N
  Y18  PB41C  BI  = CLK_GPU_2_OE_N
  Y19  PB44C  BI  = SWB_HSC_EN_R
  Y20  PR30D  BI  = NC_FPGA_PR30D
  Y21  PR29B  BI  = GPU_FPGA_RST_N
  Y22  PR28A  BI  = HP_LVC3_OCP_V3_1_HSC_PWRGD_PLD_

U252  74LVC2G17GW  IC  pkg SOT363  page 149
  1  A0  IN  = RST_PERST_SWB_R_N
  2  GND  POWER  = GND
  3  A1  IN  = RST_PERST_SWB_R_N
  4  B1  OUT  = RST_PERST_1_SWB_BUF_R_N
  5  VCC  POWER  = P3V3_AUX
  6  B0  OUT  = RST_PERST_0_SWB_BUF_R_N

U253  74LVC2G17GW  IC  pkg SOT363  page 149
  1  A0  IN  = GPU_FPGA_BOOT_EN
  2  GND  POWER  = GND
  3  A1  IN  = GPU_BASE_STBY_EN
  4  B1  OUT  = GPU_BASE_STBY_EN_BUF_R
  5  VCC  POWER  = P3V3_AUX
  6  B0  OUT  = GPU_FPGA_BOOT_EN_BUF_R

U255  74LVC2G07DW7  74LVC2G07DW-7 IC  pkg SOT363_0-65_2X1-25XC  page 150
  1  \1a\  IN  = GPU_NVS_PWR_BRAKE_N
  2  GND  POWER  = GND
  3  \2a\  IN  = GPU_FPGA_EROT_RST_N
  4  \2y\  OUT  = GPU_FPGA_EROT_RST_BUF_R_N
  5  VCC  POWER  = P3V3_AUX
  6  \1y\  OUT  = GPU_NVS_PWR_BRAKE_N_R

U256  74LVC2G17GW  IC  pkg SOT363  page 149
  1  A0  IN  = RST_PERST_SWB_R_N
  2  GND  POWER  = GND
  3  A1  IN  = FM_SWB_PWR_EN_R
  4  B1  OUT  = FM_SWB_PWR_EN_R1_BUF
  5  VCC  POWER  = P3V3_AUX
  6  B0  OUT  = RST_PERST_2_SWB_BUF_R_N

U257  74LVC2G07DW7  74LVC2G07DW-7 IC  pkg SOT363_0-65_2X1-25XC  page 150
  1  \1a\  IN  = GPU_FPGA_EROT_RECOV_N
  2  GND  POWER  = GND
  3  \2a\  IN  = GND
  4  \2y\  OUT  = NC_U257_2Y
  5  VCC  POWER  = P3V3_AUX
  6  \1y\  OUT  = GPU_FPGA_EROT_RECOV_BUF_R_N

U259  SN74LVC2G07DCKR  IC  pkg SMLF  page 190
  1  \1a\  IN  = M2_SSD0_CLKREQ_EN_N
  2  GND  POWER  = GND
  3  \2a\  IN  = RST_PCIE_PCH_DEV_PERST_M2_R_N
  4  \2y\  OUT  = RST_PCIE_PCH_DEV_BUF_M2_0_PERST
  5  VCC  POWER  = P3V3_AUX
  6  \1y\  OUT  = HDD_ACTIVITY_BUF

U263  INA230AIRGTR  IC  pkg QFN16_THXI  page 172
  1  A1  IN  = INA230_3_A1
  2  A0  IN  = INA230_3_A0
  3  ALERT  OUT  = OCP_V3_2_P3V3_ADC_ALERT_R
  4  SDA  BI  = SMB_INA230_3_3V3AUX_SDA_R1
  5  SCL  IN  = SMB_INA230_3_3V3AUX_SCL_R1
  6  NC0  OUT  = NC_INA230_3_NC0
  7  NC1  OUT  = NC_INA230_3_NC1
  8  NC2  OUT  = NC_INA230_3_NC2
  9  VS  POWER  = P3V3_AUX
  10  GND  POWER  = GND
  11  \bus\  IN  = P3V3_OCP_V3_2_R
  12  \in-\  IN  = VSENSE_P12V_INA230_3_INN
  13  \in+\  IN  = VSENSE_P12V_INA230_3_INP
  14  NC3  OUT  = NC_INA230_3_NC3
  15  NC4  OUT  = NC_INA230_3_NC4
  16  NC5  OUT  = NC_INA230_3_NC5
  TH  TH  POWER  = GND

U264  INA230AIRGTR  IC  pkg QFN16_THXI  page 172
  1  A1  IN  = INA230_4_A1
  2  A0  IN  = INA230_4_A0
  3  ALERT  OUT  = M2_0_P3V3_ADC_ALERT_R
  4  SDA  BI  = SMB_INA230_4_3V3AUX_SDA_R1
  5  SCL  IN  = SMB_INA230_4_3V3AUX_SCL_R1
  6  NC0  OUT  = NC_INA230_4_NC0
  7  NC1  OUT  = NC_INA230_4_NC1
  8  NC2  OUT  = NC_INA230_4_NC2
  9  VS  POWER  = P3V3_AUX
  10  GND  POWER  = GND
  11  \bus\  IN  = P3V3
  12  \in-\  IN  = VSENSE_P12V_INA230_4_INN
  13  \in+\  IN  = VSENSE_P12V_INA230_4_INP
  14  NC3  OUT  = NC_INA230_4_NC3
  15  NC4  OUT  = NC_INA230_4_NC4
  16  NC5  OUT  = NC_INA230_4_NC5
  TH  TH  POWER  = GND

U265  INA230AIRGTR  IC  pkg QFN16_THXI  page 172
  1  A1  IN  = INA230_5_A1
  2  A0  IN  = INA230_5_A0
  3  ALERT  OUT  = P12V_SCM_ADC_ALERT_R
  4  SDA  BI  = SMB_INA230_5_3V3AUX_SDA_R1
  5  SCL  IN  = SMB_INA230_5_3V3AUX_SCL_R1
  6  NC0  OUT  = NC_INA230_5_NC0
  7  NC1  OUT  = NC_INA230_5_NC1
  8  NC2  OUT  = NC_INA230_5_NC2
  9  VS  POWER  = P3V3_AUX
  10  GND  POWER  = GND
  11  \bus\  IN  = P12V_SCM_R
  12  \in-\  IN  = VSENSE_P12V_INA230_5_INN
  13  \in+\  IN  = VSENSE_P12V_INA230_5_INP
  14  NC3  OUT  = NC_INA230_5_NC3
  15  NC4  OUT  = NC_INA230_5_NC4
  16  NC5  OUT  = NC_INA230_5_NC5
  TH  TH  POWER  = GND

U266  INA230AIRGTR  IC  pkg QFN16_THXI  page 171
  1  A1  IN  = INA230_1_A1
  2  A0  IN  = INA230_1_A0
  3  ALERT  OUT  = OCP_SFF_P3V3_ADC_ALERT_R
  4  SDA  BI  = SMB_INA230_1_3V3AUX_SDA_R1
  5  SCL  IN  = SMB_INA230_1_3V3AUX_SCL_R1
  6  NC0  OUT  = NC_INA230_1_NC0
  7  NC1  OUT  = NC_INA230_1_NC1
  8  NC2  OUT  = NC_INA230_1_NC2
  9  VS  POWER  = P3V3_AUX
  10  GND  POWER  = GND
  11  \bus\  IN  = P3V3_OCP_SFF_R
  12  \in-\  IN  = VSENSE_P3V3_INA230_1_INN
  13  \in+\  IN  = VSENSE_P3V3_INA230_1_INP
  14  NC3  OUT  = NC_INA230_1_NC3
  15  NC4  OUT  = NC_INA230_1_NC4
  16  NC5  OUT  = NC_INA230_1_NC5
  TH  TH  POWER  = GND

U268  GL852GOHY60  GL852G-OHY60 IC  pkg QFN28_THXL  page 152
  1  DM0  BI  = USB2_P0_R_DN
  2  DP0  BI  = USB2_P0_R_DP
  3  DM1  BI  = USB2_HUB_SWB_DN
  4  DP1  BI  = USB2_HUB_SWB_DP
  5  AVDD(0)  POWER  = P3V3_AUX_USB_HUB
  6  DM2  BI  = NC_USB_HUB_DM2
  7  DP2  BI  = NC_USB_HUB_DP2
  8  RREF  IN  = USB_HUB_RREF
  9  AVDD(1)  POWER  = P3V3_AUX_USB_HUB
  10  X1  IN  = USB_HUB_XTAL_IN
  11  X2  OUT  = USB_HUB_XTAL_OUT
  12  DM3  BI  = NC_USB_HUB_DM3
  13  DP3  BI  = NC_USB_HUB_DP3
  14  AVDD(2)  POWER  = P3V3_AUX_USB_HUB
  15  DM4  BI  = NC_USB_HUB_DM4
  16  DP4  BI  = NC_USB_HUB_DP4
  17  \reset#\  IN  = RST_USB_HUB_R_N
  18  \test||scl\  BI  = USB_HUB_TEST
  19  \ovcur4#\  IN  = USB_HUB_OVCUR4
  20  \ovcur3#\  IN  = USB_HUB_OVCUR3
  21  DVDD  POWER  = USB_HUB_DVDD
  22  PSELF  IN  = USB_HUB_PSELF
  23  PGANG  BI  = USB_HUB_PGANG
  24  \ovcur2#||smd\  BI  = USB_HUB_OVCUR2
  25  \ovcur1#||smc\  IN  = USB_HUB_OVCUR1
  26  SDA  BI  = NC_USB_HUB_SDA
  27  V5  POWER  = P3V3_AUX_USB_HUB
  28  V33  POWER  = P3V3_AUX_USB_HUB
  TH  TH  POWER  = GND

U269  ADC128D818CIMTXNOPB  ADC128D818CIMTX/NOPB IC  pkg TSSOP16XC  page 250
  1  VREF  IN  = ADC128_VREF
  2  SDA  BI  = SMB_SEN_TIC_3V3AUX_SDA
  3  SCL  IN  = SMB_SEN_TIC_3V3AUX_SCL
  4  GND  POWER  = GND
  5  \v+\  POWER  = P3V3_ADC128_VCC
  6  \int#\  OUT  = TP_ADC128_INT
  7  A0  IN  = ADC128_A0
  8  A1  IN  = ADC128_A1
  9  IN7  IN  = P12V_E1S_0_ISENSE_TIC
  10  IN6  IN  = P3V3_PDB_AUX_ADC_TIC
  11  IN5  IN  = P3V3_AUX_ADC_TIC
  12  IN4  IN  = P3V3_ADC_TIC
  13  IN3  IN  = P5V_ADC_TIC
  14  IN2  IN  = P12V_OCP_V3_2_ISENSE_TIC
  15  IN1  IN  = P12V_OCP_SFF_ISENSE_TIC
  16  IN0  IN  = P12V_AUX_ADC_TIC

U270  LM75BD  IC  pkg SO8_1-27_4-9X3-9  page 170
  1  SDA  BI  = SMB_LM75_0_3V3AUX_SDA_R1
  2  SCL  IN  = SMB_LM75_0_3V3AUX_SCL_R1
  3  OS  OUT  = FM_G751_0_ALERT_N
  4  GND  POWER  = GND
  5  A2  IN  = U270_0_ADD2
  6  A1  IN  = U270_0_ADD1
  7  A0  IN  = U270_0_ADD0
  8  VCC  POWER  = P3V3_AUX

U271  LM75BD  IC  pkg SO8_1-27_4-9X3-9  page 170
  1  SDA  BI  = SMB_LM75_1_3V3AUX_SDA_R1
  2  SCL  IN  = SMB_LM75_1_3V3AUX_SCL_R1
  3  OS  OUT  = FM_G751_1_ALERT_N
  4  GND  POWER  = GND
  5  A2  IN  = U271_1_ADD2
  6  A1  IN  = U271_1_ADD1
  7  A0  IN  = U271_1_ADD0
  8  VCC  POWER  = P3V3_AUX

U272  LM75BD  IC  pkg SO8_1-27_4-9X3-9  page 170
  1  SDA  BI  = SMB_LM75_2_3V3AUX_SDA_R1
  2  SCL  IN  = SMB_LM75_2_3V3AUX_SCL_R1
  3  OS  OUT  = FM_LM75_2_ALERT_N
  4  GND  POWER  = GND
  5  A2  IN  = U272_2_ADD2
  6  A1  IN  = U272_2_ADD1
  7  A0  IN  = U272_2_ADD0
  8  VCC  POWER  = P3V3_AUX

U273  LM75BD  IC  pkg SO8_1-27_4-9X3-9  page 170
  1  SDA  BI  = SMB_LM75_3_3V3AUX_SDA_R1
  2  SCL  IN  = SMB_LM75_3_3V3AUX_SCL_R1
  3  OS  OUT  = FM_LM75_3_ALERT_N
  4  GND  POWER  = GND
  5  A2  IN  = U273_3_ADD2
  6  A1  IN  = U273_3_ADD1
  7  A0  IN  = U273_3_ADD0
  8  VCC  POWER  = P3V3_AUX

U276  INA230AIRGTR  IC  pkg QFN16_THXI  page 171
  1  A1  IN  = INA230_2_A1
  2  A0  IN  = INA230_2_A0
  3  ALERT  OUT  = E1S_0_P3V3_ADC_ALERT_R
  4  SDA  BI  = SMB_INA230_2_3V3AUX_SDA_R1
  5  SCL  IN  = SMB_INA230_2_3V3AUX_SCL_R1
  6  NC0  OUT  = NC_INA230_2_NC0
  7  NC1  OUT  = NC_INA230_2_NC1
  8  NC2  OUT  = NC_INA230_2_NC2
  9  VS  POWER  = P3V3_AUX
  10  GND  POWER  = GND
  11  \bus\  IN  = P3V3_E1S_0_R
  12  \in-\  IN  = VSENSE_P3V3_INA230_2_INN
  13  \in+\  IN  = VSENSE_P3V3_INA230_2_INP
  14  NC3  OUT  = NC_INA230_2_NC3
  15  NC4  OUT  = NC_INA230_2_NC4
  16  NC5  OUT  = NC_INA230_2_NC5
  TH  TH  POWER  = GND

U278  74LVC1G08W57  74LVC1G08W5-7 IC  pkg SOT25-5_0-95_3X1-6  page 246
  1  A  IN  = FM_GPU_HSC_EN
  2  B  IN  = GPU_PRSNT_R
  3  GND  POWER  = GND
  4  Y  OUT  = FM_GPU_HSC_EN_BUF_R
  5  VCC  POWER  = P3V3_AUX

U279  PCA9617ADP  IC  pkg TSSOP8_3XB  page 194
  1  VCCA  POWER  = P3V3_E1S_0
  2  SCLA  BI  = SMB_E1S_3V3AUX_ISO_SCL_R
  3  SDAA  BI  = SMB_E1S_3V3AUX_ISO_SDA_R
  4  GND  POWER  = GND
  5  EN  IN  = SMB_PCIE_E1S_ISO_EN_R
  6  SDAB  BI  = SMB_SENSOR_E1S_3V3AUX_SDA
  7  SCLB  BI  = SMB_SENSOR_E1S_3V3AUX_SCL
  8  VCCB  POWER  = P3V3_AUX

U286  74LVC1G126SE7  74LVC1G126SE-7 IC  pkg SOT353_0-65_2X1-25  page 160
  1  OE  IN  = OCP_V3_2_AUX_PWR_EN_R1
  2  A  IN  = FM_OCP_V3_2_PWR_GOOD
  3  GND  POWER  = GND
  4  Y  OUT  = FB_BMC_ISOLATE_R2
  5  VCC  POWER  = P3V3_AUX

U290  MOSFET_NCH_GDS_ESD_PROTECTED  2N7002K IC  pkg SOT23_GDSXC  page 301
  D  D  BI  = HSC_EN
  G  G  IN  = PDB_PRSNT_N
  S  S  BI  = GND
